#ISCELL
  mstr_symbols design_note *
  *
#ISCELL
  mstr_symbols intel_corp_bpage *
  *
#CELL
  mstr_discrete cap *
  page42_i10
#CELL
  dev_discrete cap_a *
  page42_i100
#ISCELL
  mstr_symbols gnd *
  page42_i101
#CELL
  dev_discrete cap_a *
  page42_i102
#CELL
  dev_discrete cap_a *
  page42_i103
#CELL
  dev_discrete cap_a *
  page42_i104
#ISCELL
  mstr_symbols gnd *
  page42_i105
#CELL
  dev_discrete cap_a *
  page42_i106
#CELL
  dev_discrete cap_a *
  page42_i107
#CELL
  mstr_discrete cap *
  page42_i108
#CELL
  dev_discrete cap_a *
  page42_i109
#ISCELL
  mstr_symbols gnd *
  page42_i110
#CELL
  dev_discrete cap_a *
  page42_i111
#CELL
  dev_discrete cap_a *
  page42_i114
#CELL
  dev_discrete cap_a *
  page42_i115
#ISCELL
  mstr_symbols pvccin_cpu0 *
  page42_i116
#CELL
  dev_discrete cap_a *
  page42_i117
#CELL
  dev_discrete cap_a *
  page42_i118
#ISCELL
  mstr_symbols pvccin_cpu0 *
  page42_i119
#CELL
  mstr_discrete cap *
  page42_i12
#ISCELL
  mstr_symbols pvccin_cpu0 *
  page42_i121
#ISCELL
  mstr_symbols gnd *
  page42_i122
#CELL
  dev_discrete cap_a *
  page42_i123
#ISCELL
  mstr_symbols gnd *
  page42_i124
#CELL
  dev_discrete cap_a *
  page42_i125
#CELL
  dev_discrete cap_a *
  page42_i128
#CELL
  dev_discrete cap_a *
  page42_i131
#CELL
  dev_discrete cap_a *
  page42_i132
#ISCELL
  mstr_symbols gnd *
  page42_i133
#CELL
  dev_discrete cap_a *
  page42_i134
#CELL
  dev_discrete cap_a *
  page42_i135
#ISCELL
  mstr_symbols pvccin_cpu0 *
  page42_i137
#CELL
  dev_discrete cap_a *
  page42_i138
#ISCELL
  mstr_symbols pvccin_cpu0 *
  page42_i139
#CELL
  dev_discrete cap_a *
  page42_i140
#ISCELL
  mstr_symbols pvccin_cpu0 *
  page42_i141
#CELL
  dev_discrete cap_a *
  page42_i142
#ISCELL
  mstr_symbols vcc_core *
  page42_i144
#CELL
  dev_discrete cap_a *
  page42_i145
#CELL
  dev_discrete cap_a *
  page42_i147
#CELL
  dev_discrete cap_a *
  page42_i151
#CELL
  dev_discrete cap_a *
  page42_i152
#CELL
  dev_discrete cap_a *
  page42_i153
#CELL
  dev_discrete cap_a *
  page42_i154
#CELL
  dev_discrete cap_a *
  page42_i155
#CELL
  dev_discrete cap_a *
  page42_i156
#ISCELL
  mstr_symbols vcc_core *
  page42_i159
#ISCELL
  mstr_symbols pvccio_cpu0 *
  page42_i16
#CELL
  dev_discrete cap_a *
  page42_i164
#CELL
  mstr_discrete cap *
  page42_i17
#CELL
  dev_discrete cap_a *
  page42_i173
#CELL
  dev_discrete cap_a *
  page42_i174
#CELL
  dev_discrete cap_a *
  page42_i175
#CELL
  dev_discrete cap_a *
  page42_i176
#CELL
  dev_discrete cap_a *
  page42_i178
#CELL
  dev_discrete cap_a *
  page42_i179
#CELL
  dev_discrete cap_a *
  page42_i180
#ISCELL
  mstr_symbols vcc_core *
  page42_i181
#CELL
  mstr_discrete cap *
  page42_i187
#CELL
  mstr_discrete cap *
  page42_i188
#CELL
  mstr_discrete cap *
  page42_i190
#ISCELL
  mstr_symbols pvccin_cpu0 *
  page42_i196
#ISCELL
  mstr_symbols gnd *
  page42_i20
#ISCELL
  mstr_symbols pvccin_cpu0 *
  page42_i203
#ISCELL
  mstr_symbols gnd *
  page42_i206
#ISCELL
  mstr_symbols pvccin_cpu0 *
  page42_i208
#ISCELL
  mstr_symbols gnd *
  page42_i21
#ISCELL
  mstr_symbols gnd *
  page42_i210
#CELL
  mstr_discrete cap *
  page42_i211
#ISCELL
  mstr_symbols gnd *
  page42_i212
#ISCELL
  mstr_symbols pvccin_cpu0 *
  page42_i213
#CELL
  mstr_discrete cap *
  page42_i214
#CELL
  mstr_discrete cap *
  page42_i215
#ISCELL
  mstr_symbols vcc_core *
  page42_i216
#CELL
  dev_discrete cap_a *
  page42_i217
#CELL
  dev_discrete cap_a *
  page42_i218
#ISCELL
  mstr_symbols gnd *
  page42_i219
#CELL
  mstr_discrete cap *
  page42_i220
#CELL
  mstr_discrete cap *
  page42_i221
#CELL
  mstr_discrete cap *
  page42_i222
#CELL
  mstr_discrete cap *
  page42_i223
#CELL
  mstr_discrete cap *
  page42_i224
#CELL
  mstr_discrete cap *
  page42_i225
#CELL
  mstr_discrete cap *
  page42_i226
#CELL
  mstr_discrete cap *
  page42_i227
#CELL
  mstr_discrete cap *
  page42_i228
#CELL
  mstr_discrete cap *
  page42_i229
#CELL
  mstr_discrete cap *
  page42_i230
#CELL
  mstr_discrete cap *
  page42_i231
#CELL
  mstr_discrete cap *
  page42_i232
#CELL
  mstr_discrete cap *
  page42_i233
#CELL
  mstr_discrete cap *
  page42_i234
#CELL
  mstr_discrete cap *
  page42_i235
#CELL
  mstr_discrete cap *
  page42_i236
#ISCELL
  mstr_symbols gnd *
  page42_i237
#ISCELL
  mstr_symbols pvsa_cpu0 *
  page42_i24
#CELL
  mstr_discrete cap *
  page42_i25
#CELL
  mstr_discrete cap *
  page42_i28
#ISCELL
  mstr_symbols gnd *
  page42_i32
#CELL
  mstr_discrete cap *
  page42_i33
#ISCELL
  mstr_symbols gnd *
  page42_i35
#CELL
  mstr_discrete cap *
  page42_i37
#CELL
  mstr_discrete cap *
  page42_i41
#ISCELL
  mstr_symbols pvccin_cpu0 *
  page42_i43
#CELL
  mstr_discrete cap *
  page42_i44
#ISCELL
  mstr_symbols pvccin_cpu0 *
  page42_i45
#ISCELL
  mstr_symbols gnd *
  page42_i46
#ISCELL
  mstr_symbols gnd *
  page42_i48
#ISCELL
  mstr_symbols gnd *
  page42_i5
#CELL
  mstr_discrete cap *
  page42_i50
#CELL
  mstr_discrete cap *
  page42_i51
#CELL
  mstr_discrete cap *
  page42_i53
#CELL
  mstr_discrete cap *
  page42_i54
#CELL
  mstr_discrete cap *
  page42_i55
#CELL
  mstr_discrete cap *
  page42_i56
#CELL
  mstr_discrete cap *
  page42_i57
#ISCELL
  mstr_symbols gnd *
  page42_i58
#ISCELL
  mstr_symbols pvccin_cpu0 *
  page42_i62
#CELL
  mstr_discrete cap *
  page42_i63
#ISCELL
  mstr_symbols pvccin_cpu0 *
  page42_i64
#CELL
  mstr_discrete cap *
  page42_i65
#CELL
  dev_discrete cap_a *
  page42_i68
#CELL
  dev_discrete cap_a *
  page42_i69
#CELL
  dev_discrete cap_a *
  page42_i70
#ISCELL
  mstr_symbols gnd *
  page42_i71
#CELL
  dev_discrete cap_a *
  page42_i72
#ISCELL
  mstr_symbols gnd *
  page42_i73
#CELL
  dev_discrete cap_a *
  page42_i74
#CELL
  dev_discrete cap_a *
  page42_i75
#CELL
  dev_discrete cap_a *
  page42_i77
#ISCELL
  mstr_symbols pvccio_cpu0 *
  page42_i79
#CELL
  dev_discrete cap_a *
  page42_i80
#CELL
  dev_discrete cap_a *
  page42_i81
#CELL
  dev_discrete cap_a *
  page42_i83
#CELL
  dev_discrete cap_a *
  page42_i88
#CELL
  dev_discrete cap_a *
  page42_i89
#CELL
  dev_discrete cap_a *
  page42_i90
#CELL
  mstr_discrete cap *
  page42_i91
#ISCELL
  mstr_symbols gnd *
  page42_i92
#CELL
  mstr_discrete cap *
  page42_i93
#CELL
  mstr_discrete cap *
  page42_i94
#CELL
  dev_discrete cap_a *
  page42_i98
#ISCELL
  mstr_symbols pvsa_cpu0 *
  page42_i99
